(kicad_pcb
	(version 20241229)
	(generator "pcbnew")
	(generator_version "9.0")
	(general
		(thickness 1.62)
		(legacy_teardrops no)
	)
	(paper "A4")
	(title_block
		(title "OCuLink to 10GbE adapter")
		(date "2026-02-23")
		(rev "1.1.0")
		(company "Antmicro Ltd")
		(comment 1 "www.antmicro.com")
		(comment 9 "footprints 317-321 of 510")
	)
	(layers
		(0 "F.Cu" signal)
		(4 "In1.Cu" signal)
		(6 "In2.Cu" signal)
		(8 "In3.Cu" signal)
		(10 "In4.Cu" signal)
		(12 "In5.Cu" signal)
		(14 "In6.Cu" signal)
		(2 "B.Cu" signal)
		(9 "F.Adhes" user "F.Adhesive")
		(11 "B.Adhes" user "B.Adhesive")
		(13 "F.Paste" user)
		(15 "B.Paste" user)
		(5 "F.SilkS" user "F.Silkscreen")
		(7 "B.SilkS" user "B.Silkscreen")
		(1 "F.Mask" user)
		(3 "B.Mask" user)
		(17 "Dwgs.User" user "User.Drawings")
		(19 "Cmts.User" user "User.Comments")
		(21 "Eco1.User" user "User.Eco1")
		(23 "Eco2.User" user "User.Eco2")
		(25 "Edge.Cuts" user)
		(27 "Margin" user)
		(31 "F.CrtYd" user "F.Courtyard")
		(29 "B.CrtYd" user "B.Courtyard")
		(35 "F.Fab" user)
		(33 "B.Fab" user)
	)
	(footprint "antmicro-footprints:C_0402_1005Metric"
		(layer "B.Cu")
		(at 66 132.39)
		(descr "Capacitor SMD 0402")
		(tags "capacitor SMD 0402")
		(property "Reference" "C57"
			(at -3 -0.3 0)
			(layer "B.SilkS")
			(effects
				(font
					(size 0.7 0.7)
					(thickness 0.15)
				)
				(justify right top mirror)
			)
		)
		(property "Value" "C_1u_25V_0402"
			(at -1.022927 -2.155213 0)
			(layer "B.Fab")
			(hide yes)
			(effects
				(font
					(size 0.7 0.7)
					(thickness 0.15)
				)
				(justify right top mirror)
			)
		)
		(property "Datasheet" "https://www.murata.com/products/productdetail?partno=GRM155R61E105KE11%23"
			(at 0 0 0)
			(layer "B.Fab")
			(hide yes)
			(effects
				(font
					(size 1.27 1.27)
					(thickness 0.15)
				)
				(justify mirror)
			)
		)
		(property "Description" "SMD Multilayer Ceramic Capacitor, 1 µF, 25 V, 0402 [1005 Metric], ± 10%, X5R, GRM Series"
			(at 0 0 0)
			(layer "B.Fab")
			(hide yes)
			(effects
				(font
					(size 1.27 1.27)
					(thickness 0.15)
				)
				(justify mirror)
			)
		)
		(property "MPN" "GRM155R61E105KE11J"
			(at 0 0 0)
			(unlocked yes)
			(layer "B.Fab")
			(hide yes)
			(effects
				(font
					(size 1 1)
					(thickness 0.15)
				)
				(justify mirror)
			)
		)
		(property "Manufacturer" "Murata"
			(at 0 0 0)
			(unlocked yes)
			(layer "B.Fab")
			(hide yes)
			(effects
				(font
					(size 1 1)
					(thickness 0.15)
				)
				(justify mirror)
			)
		)
		(property "License" "Apache-2.0"
			(at 0 0 0)
			(unlocked yes)
			(layer "B.Fab")
			(hide yes)
			(effects
				(font
					(size 1 1)
					(thickness 0.15)
				)
				(justify mirror)
			)
		)
		(property "Author" "Antmicro"
			(at 0 0 0)
			(unlocked yes)
			(layer "B.Fab")
			(hide yes)
			(effects
				(font
					(size 1 1)
					(thickness 0.15)
				)
				(justify mirror)
			)
		)
		(property "Val" "1u"
			(at 0 0 0)
			(unlocked yes)
			(layer "B.Fab")
			(hide yes)
			(effects
				(font
					(size 1 1)
					(thickness 0.15)
				)
				(justify mirror)
			)
		)
		(property "Voltage" "25V"
			(at 0 0 0)
			(unlocked yes)
			(layer "B.Fab")
			(hide yes)
			(effects
				(font
					(size 1 1)
					(thickness 0.15)
				)
				(justify mirror)
			)
		)
		(property "Dielectric" "X5R"
			(at 0 0 0)
			(unlocked yes)
			(layer "B.Fab")
			(hide yes)
			(effects
				(font
					(size 1 1)
					(thickness 0.15)
				)
				(justify mirror)
			)
		)
		(sheetname "/2xRJ45/")
		(sheetfile "2xrj45.kicad_sch")
		(attr smd)
		(fp_rect
			(start -0.925 0.47)
			(end 0.925 -0.47)
			(stroke
				(width 0.05)
				(type default)
			)
			(fill no)
			(layer "B.CrtYd")
		)
		(fp_line
			(start -0.494 -0.248)
			(end -0.494 0.25)
			(stroke
				(width 0.15)
				(type solid)
			)
			(layer "B.Fab")
		)
		(fp_line
			(start -0.494 0.25)
			(end 0.504 0.25)
			(stroke
				(width 0.15)
				(type solid)
			)
			(layer "B.Fab")
		)
		(fp_line
			(start 0.504 -0.248)
			(end -0.494 -0.248)
			(stroke
				(width 0.15)
				(type solid)
			)
			(layer "B.Fab")
		)
		(fp_line
			(start 0.504 0.25)
			(end 0.504 -0.248)
			(stroke
				(width 0.15)
				(type solid)
			)
			(layer "B.Fab")
		)
		(pad "1" smd roundrect
			(at -0.48 0)
			(size 0.59 0.64)
			(layers "B.Cu" "B.Mask" "B.Paste")
			(roundrect_rratio 0.25)
			(net 28 "GND")
			(pintype "passive")
		)
		(pad "2" smd roundrect
			(at 0.48 0)
			(size 0.59 0.64)
			(layers "B.Cu" "B.Mask" "B.Paste")
			(roundrect_rratio 0.25)
			(net 299 "/2xRJ45/P0_CT")
			(pintype "passive")
		)
	)
	(footprint "antmicro-footprints:TP_SMD_1mm"
		(layer "B.Cu")
		(at 84.74 72.3 -90)
		(property "Reference" "TP36"
			(at -1.9 9.816204 90)
			(layer "B.SilkS")
			(effects
				(font
					(size 0.7 0.7)
					(thickness 0.15)
				)
				(justify left bottom mirror)
			)
		)
		(property "Value" "TP_1mm_SMD"
			(at 0 -1.4 90)
			(layer "B.Fab")
			(hide yes)
			(effects
				(font
					(size 0.7 0.7)
					(thickness 0.15)
				)
				(justify left bottom mirror)
			)
		)
		(property "Description" "Test point 1mm SMD"
			(at 0 0 90)
			(layer "B.Fab")
			(hide yes)
			(effects
				(font
					(size 1.27 1.27)
					(thickness 0.15)
				)
				(justify mirror)
			)
		)
		(property "MPN" ""
			(at 0 0 90)
			(unlocked yes)
			(layer "B.Fab")
			(hide yes)
			(effects
				(font
					(size 1 1)
					(thickness 0.15)
				)
				(justify mirror)
			)
		)
		(property "Manufacturer" ""
			(at 0 0 90)
			(unlocked yes)
			(layer "B.Fab")
			(hide yes)
			(effects
				(font
					(size 1 1)
					(thickness 0.15)
				)
				(justify mirror)
			)
		)
		(property "Author" "Antmicro"
			(at 0 0 90)
			(unlocked yes)
			(layer "B.Fab")
			(hide yes)
			(effects
				(font
					(size 1 1)
					(thickness 0.15)
				)
				(justify mirror)
			)
		)
		(property "License" "Apache-2.0"
			(at 0 0 90)
			(unlocked yes)
			(layer "B.Fab")
			(hide yes)
			(effects
				(font
					(size 1 1)
					(thickness 0.15)
				)
				(justify mirror)
			)
		)
		(sheetname "/Fan controller/")
		(sheetfile "fan-controller.kicad_sch")
		(attr exclude_from_pos_files exclude_from_bom dnp)
		(fp_circle
			(center 0 0)
			(end 0.6 0)
			(stroke
				(width 0.05)
				(type default)
			)
			(fill no)
			(layer "B.CrtYd")
		)
		(pad "1" smd circle
			(at 0 0 270)
			(size 1 1)
			(layers "B.Cu" "B.Mask")
			(net 388 "/Fan controller/+5V")
			(pinfunction "1")
			(pintype "passive")
		)
	)
	(footprint "antmicro-footprints:R_0402_1005Metric"
		(layer "B.Cu")
		(at 109.5 69.6 180)
		(descr "Resistor SMD 0402")
		(tags "resistor SMD 0402")
		(property "Reference" "R168"
			(at -1.44 5.61 0)
			(layer "B.SilkS")
			(effects
				(font
					(size 0.7 0.7)
					(thickness 0.15)
				)
				(justify left bottom mirror)
			)
		)
		(property "Value" "R_0R_0402"
			(at -1.011843 -1.772046 0)
			(layer "B.Fab")
			(hide yes)
			(effects
				(font
					(size 0.7 0.7)
					(thickness 0.15)
				)
				(justify left bottom mirror)
			)
		)
		(property "Datasheet" "https://industrial.panasonic.com/cdbs/www-data/pdf/RDA0000/AOA0000C301.pdf"
			(at 0 0 0)
			(layer "B.Fab")
			(hide yes)
			(effects
				(font
					(size 1.27 1.27)
					(thickness 0.15)
				)
				(justify mirror)
			)
		)
		(property "Description" "SMD Chip Resistor, Jumper, 0 ohm, 100 mW, 0402 [1005 Metric], Thick Film, General Purpose"
			(at 0 0 0)
			(layer "B.Fab")
			(hide yes)
			(effects
				(font
					(size 1.27 1.27)
					(thickness 0.15)
				)
				(justify mirror)
			)
		)
		(property "MPN" "ERJ2GE0R00X"
			(at 0 0 180)
			(unlocked yes)
			(layer "B.Fab")
			(hide yes)
			(effects
				(font
					(size 1 1)
					(thickness 0.15)
				)
				(justify mirror)
			)
		)
		(property "Manufacturer" "Panasonic"
			(at 0 0 180)
			(unlocked yes)
			(layer "B.Fab")
			(hide yes)
			(effects
				(font
					(size 1 1)
					(thickness 0.15)
				)
				(justify mirror)
			)
		)
		(property "License" "Apache-2.0"
			(at 0 0 180)
			(unlocked yes)
			(layer "B.Fab")
			(hide yes)
			(effects
				(font
					(size 1 1)
					(thickness 0.15)
				)
				(justify mirror)
			)
		)
		(property "Author" "Antmicro"
			(at 0 0 180)
			(unlocked yes)
			(layer "B.Fab")
			(hide yes)
			(effects
				(font
					(size 1 1)
					(thickness 0.15)
				)
				(justify mirror)
			)
		)
		(property "Val" "0R"
			(at 0 0 180)
			(unlocked yes)
			(layer "B.Fab")
			(hide yes)
			(effects
				(font
					(size 1 1)
					(thickness 0.15)
				)
				(justify mirror)
			)
		)
		(property "Tolerance" "~"
			(at 0 0 180)
			(unlocked yes)
			(layer "B.Fab")
			(hide yes)
			(effects
				(font
					(size 1 1)
					(thickness 0.15)
				)
				(justify mirror)
			)
		)
		(property "Current" "1A"
			(at 0 0 180)
			(unlocked yes)
			(layer "B.Fab")
			(hide yes)
			(effects
				(font
					(size 1 1)
					(thickness 0.15)
				)
				(justify mirror)
			)
		)
		(sheetname "/OCuLink/")
		(sheetfile "oculink.kicad_sch")
		(attr smd)
		(fp_rect
			(start -0.925 0.47)
			(end 0.925 -0.47)
			(stroke
				(width 0.05)
				(type default)
			)
			(fill no)
			(layer "B.CrtYd")
		)
		(fp_rect
			(start -0.5 0.25)
			(end 0.5 -0.25)
			(stroke
				(width 0.15)
				(type solid)
			)
			(fill no)
			(layer "B.Fab")
		)
		(pad "1" smd roundrect
			(at -0.48 0 180)
			(size 0.59 0.64)
			(layers "B.Cu" "B.Mask" "B.Paste")
			(roundrect_rratio 0.25)
			(net 321 "/OCuLink/~{CPRSNT}_R")
			(pintype "passive")
		)
		(pad "2" smd roundrect
			(at 0.48 0 180)
			(size 0.59 0.64)
			(layers "B.Cu" "B.Mask" "B.Paste")
			(roundrect_rratio 0.25)
			(net 393 "/OCuLink/~{CPRSNT}")
			(pintype "passive")
		)
	)
	(footprint "antmicro-footprints:C_0402_1005Metric"
		(layer "B.Cu")
		(at 78.22 103.23 90)
		(descr "Capacitor SMD 0402")
		(tags "capacitor SMD 0402")
		(property "Reference" "C182"
			(at -11.62 -0.04 90)
			(layer "B.SilkS")
			(effects
				(font
					(size 0.7 0.7)
					(thickness 0.15)
				)
				(justify right top mirror)
			)
		)
		(property "Value" "C_1u_25V_0402"
			(at -1.022927 -2.155213 90)
			(layer "B.Fab")
			(hide yes)
			(effects
				(font
					(size 0.7 0.7)
					(thickness 0.15)
				)
				(justify right top mirror)
			)
		)
		(property "Datasheet" "https://www.murata.com/products/productdetail?partno=GRM155R61E105KE11%23"
			(at 0 0 90)
			(layer "B.Fab")
			(hide yes)
			(effects
				(font
					(size 1.27 1.27)
					(thickness 0.15)
				)
				(justify mirror)
			)
		)
		(property "Description" "SMD Multilayer Ceramic Capacitor, 1 µF, 25 V, 0402 [1005 Metric], ± 10%, X5R, GRM Series"
			(at 0 0 90)
			(layer "B.Fab")
			(hide yes)
			(effects
				(font
					(size 1.27 1.27)
					(thickness 0.15)
				)
				(justify mirror)
			)
		)
		(property "MPN" "GRM155R61E105KE11J"
			(at 0 0 90)
			(unlocked yes)
			(layer "B.Fab")
			(hide yes)
			(effects
				(font
					(size 1 1)
					(thickness 0.15)
				)
				(justify mirror)
			)
		)
		(property "Manufacturer" "Murata"
			(at 0 0 90)
			(unlocked yes)
			(layer "B.Fab")
			(hide yes)
			(effects
				(font
					(size 1 1)
					(thickness 0.15)
				)
				(justify mirror)
			)
		)
		(property "License" "Apache-2.0"
			(at 0 0 90)
			(unlocked yes)
			(layer "B.Fab")
			(hide yes)
			(effects
				(font
					(size 1 1)
					(thickness 0.15)
				)
				(justify mirror)
			)
		)
		(property "Author" "Antmicro"
			(at 0 0 90)
			(unlocked yes)
			(layer "B.Fab")
			(hide yes)
			(effects
				(font
					(size 1 1)
					(thickness 0.15)
				)
				(justify mirror)
			)
		)
		(property "Val" "1u"
			(at 0 0 90)
			(unlocked yes)
			(layer "B.Fab")
			(hide yes)
			(effects
				(font
					(size 1 1)
					(thickness 0.15)
				)
				(justify mirror)
			)
		)
		(property "Voltage" "25V"
			(at 0 0 90)
			(unlocked yes)
			(layer "B.Fab")
			(hide yes)
			(effects
				(font
					(size 1 1)
					(thickness 0.15)
				)
				(justify mirror)
			)
		)
		(property "Dielectric" "X5R"
			(at 0 0 90)
			(unlocked yes)
			(layer "B.Fab")
			(hide yes)
			(effects
				(font
					(size 1 1)
					(thickness 0.15)
				)
				(justify mirror)
			)
		)
		(sheetname "/X710-AT2 power/")
		(sheetfile "x710-at2-power.kicad_sch")
		(attr smd)
		(fp_rect
			(start -0.925 0.47)
			(end 0.925 -0.47)
			(stroke
				(width 0.05)
				(type default)
			)
			(fill no)
			(layer "B.CrtYd")
		)
		(fp_line
			(start 0.504 -0.248)
			(end -0.494 -0.248)
			(stroke
				(width 0.15)
				(type solid)
			)
			(layer "B.Fab")
		)
		(fp_line
			(start -0.494 -0.248)
			(end -0.494 0.25)
			(stroke
				(width 0.15)
				(type solid)
			)
			(layer "B.Fab")
		)
		(fp_line
			(start 0.504 0.25)
			(end 0.504 -0.248)
			(stroke
				(width 0.15)
				(type solid)
			)
			(layer "B.Fab")
		)
		(fp_line
			(start -0.494 0.25)
			(end 0.504 0.25)
			(stroke
				(width 0.15)
				(type solid)
			)
			(layer "B.Fab")
		)
		(pad "1" smd roundrect
			(at -0.48 0 90)
			(size 0.59 0.64)
			(layers "B.Cu" "B.Mask" "B.Paste")
			(roundrect_rratio 0.25)
			(net 28 "GND")
			(pintype "passive")
		)
		(pad "2" smd roundrect
			(at 0.48 0 90)
			(size 0.59 0.64)
			(layers "B.Cu" "B.Mask" "B.Paste")
			(roundrect_rratio 0.25)
			(net 12 "XFI_VDD")
			(pintype "passive")
		)
	)
	(footprint "antmicro-footprints:C_0402_1005Metric"
		(layer "B.Cu")
		(at 86.225 100.15 90)
		(descr "Capacitor SMD 0402")
		(tags "capacitor SMD 0402")
		(property "Reference" "C114"
			(at 9.87 -0.43151 90)
			(layer "B.SilkS")
			(effects
				(font
					(size 0.7 0.7)
					(thickness 0.15)
				)
				(justify right top mirror)
			)
		)
		(property "Value" "C_1u_25V_0402"
			(at -1.022927 -2.155213 90)
			(layer "B.Fab")
			(hide yes)
			(effects
				(font
					(size 0.7 0.7)
					(thickness 0.15)
				)
				(justify right top mirror)
			)
		)
		(property "Datasheet" "https://www.murata.com/products/productdetail?partno=GRM155R61E105KE11%23"
			(at 0 0 90)
			(layer "B.Fab")
			(hide yes)
			(effects
				(font
					(size 1.27 1.27)
					(thickness 0.15)
				)
				(justify mirror)
			)
		)
		(property "Description" "SMD Multilayer Ceramic Capacitor, 1 µF, 25 V, 0402 [1005 Metric], ± 10%, X5R, GRM Series"
			(at 0 0 90)
			(layer "B.Fab")
			(hide yes)
			(effects
				(font
					(size 1.27 1.27)
					(thickness 0.15)
				)
				(justify mirror)
			)
		)
		(property "MPN" "GRM155R61E105KE11J"
			(at 0 0 90)
			(unlocked yes)
			(layer "B.Fab")
			(hide yes)
			(effects
				(font
					(size 1 1)
					(thickness 0.15)
				)
				(justify mirror)
			)
		)
		(property "Manufacturer" "Murata"
			(at 0 0 90)
			(unlocked yes)
			(layer "B.Fab")
			(hide yes)
			(effects
				(font
					(size 1 1)
					(thickness 0.15)
				)
				(justify mirror)
			)
		)
		(property "License" "Apache-2.0"
			(at 0 0 90)
			(unlocked yes)
			(layer "B.Fab")
			(hide yes)
			(effects
				(font
					(size 1 1)
					(thickness 0.15)
				)
				(justify mirror)
			)
		)
		(property "Author" "Antmicro"
			(at 0 0 90)
			(unlocked yes)
			(layer "B.Fab")
			(hide yes)
			(effects
				(font
					(size 1 1)
					(thickness 0.15)
				)
				(justify mirror)
			)
		)
		(property "Val" "1u"
			(at 0 0 90)
			(unlocked yes)
			(layer "B.Fab")
			(hide yes)
			(effects
				(font
					(size 1 1)
					(thickness 0.15)
				)
				(justify mirror)
			)
		)
		(property "Voltage" "25V"
			(at 0 0 90)
			(unlocked yes)
			(layer "B.Fab")
			(hide yes)
			(effects
				(font
					(size 1 1)
					(thickness 0.15)
				)
				(justify mirror)
			)
		)
		(property "Dielectric" "X5R"
			(at 0 0 90)
			(unlocked yes)
			(layer "B.Fab")
			(hide yes)
			(effects
				(font
					(size 1 1)
					(thickness 0.15)
				)
				(justify mirror)
			)
		)
		(sheetname "/X710-AT2 power/")
		(sheetfile "x710-at2-power.kicad_sch")
		(attr smd)
		(fp_rect
			(start -0.925 0.47)
			(end 0.925 -0.47)
			(stroke
				(width 0.05)
				(type default)
			)
			(fill no)
			(layer "B.CrtYd")
		)
		(fp_line
			(start 0.504 -0.248)
			(end -0.494 -0.248)
			(stroke
				(width 0.15)
				(type solid)
			)
			(layer "B.Fab")
		)
		(fp_line
			(start -0.494 -0.248)
			(end -0.494 0.25)
			(stroke
				(width 0.15)
				(type solid)
			)
			(layer "B.Fab")
		)
		(fp_line
			(start 0.504 0.25)
			(end 0.504 -0.248)
			(stroke
				(width 0.15)
				(type solid)
			)
			(layer "B.Fab")
		)
		(fp_line
			(start -0.494 0.25)
			(end 0.504 0.25)
			(stroke
				(width 0.15)
				(type solid)
			)
			(layer "B.Fab")
		)
		(pad "1" smd roundrect
			(at -0.48 0 90)
			(size 0.59 0.64)
			(layers "B.Cu" "B.Mask" "B.Paste")
			(roundrect_rratio 0.25)
			(net 28 "GND")
			(pintype "passive")
		)
		(pad "2" smd roundrect
			(at 0.48 0 90)
			(size 0.59 0.64)
			(layers "B.Cu" "B.Mask" "B.Paste")
			(roundrect_rratio 0.25)
			(net 9 "VCCD")
			(pintype "passive")
		)
	)
)
